# Zaius-MB-DVT-PROGRAM_IC_LIST-X03-20170525.xls.xlsx — PLANAR FW List (ic-programming-list)
| FOXCONN TECHNOLOGY GROUP |  |  |  |  |  |  |  |  |  |  |  |  |  |  |  |
| Program IC List |  |  |  |  |  |  |  |  |  |  |  |  |  |  |  |
| Phase | DVT | CUSTOMER |  | <name> | PWA CUSTOMER P/N |  | PWA FOXCONN P/N |  | PWA DESCRIPTION | Zaius MB | PRODUCT CODE | PBA REV | X03 | DATE | 42863 |
| Location | Function | Source code version | Program Type | Bin File | Empty IC  FOXCONN PN | Empty IC  Supplier PN | Programmed IC  FOXCONN PN | CheckSUM | Program Spec | Source Code Release Date | From Whom | Comment |  |  |  |
| U37 | USB controller UPD720201, EEPROM | 0.0.1 | Off-line |  | 41050J100-233-G | MX25L5121EMC-20G | NA | 005E79C6 |  | 42853 | TAIWAN SATORI RENESAS | Updated EEPROM for 4-port enable for DVT |  |  |  |
| U46 | SATA Controller 88SE9235, FLASH | 0.0.0 | Off-line |  | 41050K700-233-G | MX25L4006EM2I-12G | NA | 03B75FF7 |  | 42401 | Marvell | As same as EVT3 |  |  |  |
| U20 | BMC AST2500, 512Mb Flash | NA | NA | Google | 410512F00-233-G | MX66L51235FMI-10G | NA | TBD |  |  | Google | Google no need the flash part for DVT shipment |  |  |  |
| U21 | BIOS, 512Mb Flash | NA | NA | FXN | 410512F00-233-G | MX66L51235FMI-10G | NA | TBD |  |  | FXN | Google no need the flash part for DVT shipment |  |  |  |
| U98 | VPD, EEPROM | DVT | Off-line | IBM | 410403P00-214-G | M24512-WMN6TP | NA | 0003AD34 |  | 42878 | IBM | For DVT build IBM updated on 5/23 |  |  |  |
| U30 | FRU, EEPROM | 0.0.0 | Off-line | FXN | 41040BT00-191-G | AT24C64D-SSHM-T | NA | 00002900 |  | 42622 | FXN | Zaius MB FRU As same as EVT3 |  |  |  |
| PAAU1,PBAU1,PAMU1,PBMU1,PAEU1,PAFU1,PBEU1,PBFU1 | VR Controller, ISL68137 |  | Vendor | INTERSIL | 320242200-230-G | ISL68137IRAZ-T | ISL68137IRAZ-GG04 | N/A |  | DVT | FXN | Update for fixing VCS writing issue Update MPN in DVT |  |  |  |
| PANU1,PBNU1 | VIO VR, IR38064 |  | Vendor | IR | 320147Q00-238-G | IR38064MTRPBF | IR38064MTRPBF | 8874 |  | EVT3 | FXN | Add yellow point in DVT Date code is C712P |  |  |  |
| U5 | Power Sequencer, UCD90160 |  | Vendor | FXN/TI | 320245T00-183-G | UCD90160RGCR | UCD90160RGCR-C10 | 012E2242 |  | 42877 | TI/FXN | Updated for VCS reading; Update for 1.05V power on sequence whch that meet USB3 controller's spec Update MPN in DVT |  |  |  |
